FILE_TYPE = CONNECTIVITY;
{Allegro Design Entry HDL 16.6-p007 (v16-6-112F) 10/10/2012}
"PAGE_NUMBER" = 25;
0"NC";
1"M_C_DQS_DP<17:0>";
2"M_C_MA<17:0>";
3"M_C_DQS_DN<17:0>";
4"M_C_ODT<3:0>";
5"M_C_CS_N<7:0>";
6"M_C_CKE<3:0>";
7"M_C_BG<1:0>";
8"M_C_BA<1:0>";
9"M_C_DQ<63:0>";
10"M_C_ECC<7:0>";
11"M_C_CLK_DP<3:0>";
12"M_C_CLK_DN<3:0>";
13"M_C_DQS_DN<7>";
14"M_C_DQ<54>";
15"M_C_DQ<40>";
16"M_C_DQS_DP<1>";
17"M_C_DQ<52>";
18"M_C_ODT<2>";
19"M_C_DQ<34>";
20"M_C_DQ<32>";
21"M_C_DQ<4>";
22"M_C_C<2>";
23"M_C_CLK_DN<3>";
24"M_C_CLK_DN<2>";
25"M_C_CLK_DN<1>";
26"M_C_CLK_DN<0>";
27"M_C_CLK_DP<3>";
28"M_C_CLK_DP<2>";
29"M_C_CLK_DP<1>";
30"M_C_CLK_DP<0>";
31"M_C_DQ<9>";
32"M_C_DQ<8>";
33"M_C_DQ<7>";
34"M_C_DQ<6>";
35"M_C_DQ<5>";
36"M_C_DQ<3>";
37"M_C_DQ<2>";
38"M_C_DQ<1>";
39"M_C_DQ<0>";
40"M_C_ECC<7>";
41"M_C_ECC<6>";
42"M_C_ECC<5>";
43"M_C_ECC<4>";
44"M_C_ECC<3>";
45"M_C_ECC<2>";
46"M_C_ECC<1>";
47"M_C_ECC<0>";
48"M_C_DQ<50>";
49"M_C_DQ<49>";
50"M_C_DQ<48>";
51"M_C_DQ<47>";
52"M_C_DQ<46>";
53"M_C_DQ<45>";
54"M_C_DQ<44>";
55"M_C_DQ<43>";
56"M_C_DQ<42>";
57"M_C_DQ<41>";
58"M_C_DQ<39>";
59"M_C_DQ<38>";
60"M_C_DQ<37>";
61"M_C_DQ<36>";
62"M_C_DQ<35>";
63"M_C_DQ<33>";
64"M_C_DQ<31>";
65"M_C_DQ<30>";
66"M_C_DQ<29>";
67"M_C_DQ<28>";
68"M_C_DQ<27>";
69"M_C_DQ<26>";
70"M_C_DQ<25>";
71"M_C_DQ<24>";
72"M_C_DQ<23>";
73"M_C_DQ<22>";
74"M_C_DQ<20>";
75"M_C_DQ<19>";
76"M_C_DQ<18>";
77"M_C_DQ<17>";
78"M_C_DQ<16>";
79"M_C_DQ<15>";
80"M_C_DQ<14>";
81"M_C_DQ<13>";
82"M_C_DQ<12>";
83"M_C_DQ<11>";
84"M_C_DQ<10>";
85"M_C_DQ<21>";
86"M_C_DQ<63>";
87"M_C_DQ<62>";
88"M_C_DQ<61>";
89"M_C_DQ<60>";
90"M_C_DQ<59>";
91"M_C_DQ<58>";
92"M_C_DQ<57>";
93"M_C_DQ<56>";
94"M_C_DQ<55>";
95"M_C_DQ<53>";
96"M_C_DQ<51>";
97"M_C_BA<1>";
98"M_C_BA<0>";
99"M_C_BG<1>";
100"M_C_BG<0>";
101"M_C_CKE<3>";
102"M_C_CKE<2>";
103"M_C_CKE<1>";
104"M_C_CKE<0>";
105"M_C_CS_N<7>";
106"M_C_CS_N<6>";
107"M_C_CS_N<5>";
108"M_C_CS_N<4>";
109"M_C_CS_N<3>";
110"M_C_CS_N<2>";
111"M_C_CS_N<1>";
112"M_C_CS_N<0>";
113"M_C_MA<1>";
114"M_C_MA<0>";
115"M_C_ODT<3>";
116"M_C_ODT<1>";
117"M_C_ODT<0>";
118"M_C_PAR";
119"M_C_ACT_N";
120"M_C_ALERT_N";
121"M_C_DQS_DN<17>";
122"M_C_DQS_DN<16>";
123"M_C_DQS_DN<15>";
124"M_C_DQS_DN<14>";
125"M_C_DQS_DN<13>";
126"M_C_DQS_DN<12>";
127"M_C_DQS_DN<11>";
128"M_C_DQS_DN<10>";
129"M_C_DQS_DN<9>";
130"M_C_DQS_DN<8>";
131"M_C_DQS_DN<6>";
132"M_C_DQS_DN<5>";
133"M_C_DQS_DN<4>";
134"M_C_DQS_DN<3>";
135"M_C_DQS_DN<2>";
136"M_C_DQS_DN<1>";
137"M_C_DQS_DN<0>";
138"M_C_DQS_DP<4>";
139"M_C_DQS_DP<3>";
140"M_C_DQS_DP<2>";
141"M_C_DQS_DP<0>";
142"M_C_MA<17>";
143"M_C_MA<16>";
144"M_C_MA<15>";
145"M_C_MA<14>";
146"M_C_MA<13>";
147"M_C_MA<12>";
148"M_C_MA<11>";
149"M_C_MA<10>";
150"M_C_MA<9>";
151"M_C_MA<8>";
152"M_C_MA<7>";
153"M_C_MA<6>";
154"M_C_MA<5>";
155"M_C_MA<4>";
156"M_C_MA<3>";
157"M_C_MA<2>";
158"M_C_DQS_DP<17>";
159"M_C_DQS_DP<16>";
160"M_C_DQS_DP<15>";
161"M_C_DQS_DP<14>";
162"M_C_DQS_DP<13>";
163"M_C_DQS_DP<12>";
164"M_C_DQS_DP<11>";
165"M_C_DQS_DP<10>";
166"M_C_DQS_DP<9>";
167"M_C_DQS_DP<8>";
168"M_C_DQS_DP<7>";
169"M_C_DQS_DP<6>";
170"M_C_DQS_DP<5>";
%"TAP"
"6","(-5575,900)","0","mstr_standard","I10";
;
HDL_TAP"TRUE"
BODY_TYPE"PLUMBING"
CDS_LIB"mstr_standard";
"B \NAC \NWC"11;
"S \NAC"
BN"1"29;
%"TAP"
"6","(-2850,1500)","2","mstr_standard","I100";
;
HDL_TAP"TRUE"
BODY_TYPE"PLUMBING"
CDS_LIB"mstr_standard";
"B \NAC \NWC"4;
"S \NAC"
BN"1"116;
%"TAP"
"6","(-2850,1550)","2","mstr_standard","I101";
;
HDL_TAP"TRUE"
BODY_TYPE"PLUMBING"
CDS_LIB"mstr_standard";
"B \NAC \NWC"4;
"S \NAC"
BN"2"18;
%"TAP"
"6","(-2850,1600)","2","mstr_standard","I102";
;
HDL_TAP"TRUE"
BODY_TYPE"PLUMBING"
CDS_LIB"mstr_standard";
"B \NAC \NWC"4;
"S \NAC"
BN"3"115;
%"TAP"
"6","(-2850,1700)","2","mstr_standard","I103";
;
HDL_TAP"TRUE"
BODY_TYPE"PLUMBING"
CDS_LIB"mstr_standard";
"B \NAC \NWC"6;
"S \NAC"
BN"0"104;
%"TAP"
"6","(-2850,1750)","2","mstr_standard","I104";
;
HDL_TAP"TRUE"
BODY_TYPE"PLUMBING"
CDS_LIB"mstr_standard";
"B \NAC \NWC"6;
"S \NAC"
BN"1"103;
%"TAP"
"6","(-2850,1800)","2","mstr_standard","I105";
;
HDL_TAP"TRUE"
BODY_TYPE"PLUMBING"
CDS_LIB"mstr_standard";
"B \NAC \NWC"6;
"S \NAC"
BN"2"102;
%"TAP"
"6","(-2850,1850)","2","mstr_standard","I106";
;
HDL_TAP"TRUE"
BODY_TYPE"PLUMBING"
CDS_LIB"mstr_standard";
"B \NAC \NWC"6;
"S \NAC"
BN"3"101;
%"TAP"
"6","(-2850,1950)","2","mstr_standard","I107";
;
HDL_TAP"TRUE"
BODY_TYPE"PLUMBING"
CDS_LIB"mstr_standard";
"B \NAC \NWC"2;
"S \NAC"
BN"0"114;
%"TAP"
"6","(-2850,2050)","2","mstr_standard","I108";
;
HDL_TAP"TRUE"
BODY_TYPE"PLUMBING"
CDS_LIB"mstr_standard";
"B \NAC \NWC"2;
"S \NAC"
BN"2"157;
%"TAP"
"6","(-2850,2000)","2","mstr_standard","I109";
;
HDL_TAP"TRUE"
BODY_TYPE"PLUMBING"
CDS_LIB"mstr_standard";
"B \NAC \NWC"2;
"S \NAC"
BN"1"113;
%"TAP"
"6","(-5575,950)","0","mstr_standard","I11";
;
HDL_TAP"TRUE"
BODY_TYPE"PLUMBING"
CDS_LIB"mstr_standard";
"B \NAC \NWC"11;
"S \NAC"
BN"2"28;
%"TAP"
"6","(-2850,2100)","2","mstr_standard","I110";
;
HDL_TAP"TRUE"
BODY_TYPE"PLUMBING"
CDS_LIB"mstr_standard";
"B \NAC \NWC"2;
"S \NAC"
BN"3"156;
%"TAP"
"6","(-2850,2150)","2","mstr_standard","I111";
;
HDL_TAP"TRUE"
BODY_TYPE"PLUMBING"
CDS_LIB"mstr_standard";
"B \NAC \NWC"2;
"S \NAC"
BN"4"155;
%"TAP"
"6","(-2850,2200)","2","mstr_standard","I112";
;
HDL_TAP"TRUE"
BODY_TYPE"PLUMBING"
CDS_LIB"mstr_standard";
"B \NAC \NWC"2;
"S \NAC"
BN"5"154;
%"TAP"
"6","(-2850,2250)","2","mstr_standard","I113";
;
HDL_TAP"TRUE"
BODY_TYPE"PLUMBING"
CDS_LIB"mstr_standard";
"B \NAC \NWC"2;
"S \NAC"
BN"6"153;
%"TAP"
"6","(-2850,2300)","2","mstr_standard","I114";
;
HDL_TAP"TRUE"
BODY_TYPE"PLUMBING"
CDS_LIB"mstr_standard";
"B \NAC \NWC"2;
"S \NAC"
BN"7"152;
%"TAP"
"6","(-2850,2350)","2","mstr_standard","I115";
;
HDL_TAP"TRUE"
BODY_TYPE"PLUMBING"
CDS_LIB"mstr_standard";
"B \NAC \NWC"2;
"S \NAC"
BN"8"151;
%"TAP"
"6","(-2850,2400)","2","mstr_standard","I116";
;
HDL_TAP"TRUE"
BODY_TYPE"PLUMBING"
CDS_LIB"mstr_standard";
"B \NAC \NWC"2;
"S \NAC"
BN"9"150;
%"TAP"
"6","(-2850,2450)","2","mstr_standard","I117";
;
HDL_TAP"TRUE"
BODY_TYPE"PLUMBING"
CDS_LIB"mstr_standard";
"B \NAC \NWC"2;
"S \NAC"
BN"10"149;
%"TAP"
"6","(-2850,2500)","2","mstr_standard","I118";
;
HDL_TAP"TRUE"
BODY_TYPE"PLUMBING"
CDS_LIB"mstr_standard";
"B \NAC \NWC"2;
"S \NAC"
BN"11"148;
%"TAP"
"6","(-2850,2550)","2","mstr_standard","I119";
;
HDL_TAP"TRUE"
BODY_TYPE"PLUMBING"
CDS_LIB"mstr_standard";
"B \NAC \NWC"2;
"S \NAC"
BN"12"147;
%"TAP"
"6","(-5575,1000)","0","mstr_standard","I12";
;
HDL_TAP"TRUE"
BODY_TYPE"PLUMBING"
CDS_LIB"mstr_standard";
"B \NAC \NWC"11;
"S \NAC"
BN"3"27;
%"TAP"
"6","(-2850,2600)","2","mstr_standard","I120";
;
HDL_TAP"TRUE"
BODY_TYPE"PLUMBING"
CDS_LIB"mstr_standard";
"B \NAC \NWC"2;
"S \NAC"
BN"13"146;
%"TAP"
"6","(-2850,2650)","2","mstr_standard","I121";
;
HDL_TAP"TRUE"
BODY_TYPE"PLUMBING"
CDS_LIB"mstr_standard";
"B \NAC \NWC"2;
"S \NAC"
BN"14"145;
%"TAP"
"6","(-2850,2700)","2","mstr_standard","I122";
;
HDL_TAP"TRUE"
BODY_TYPE"PLUMBING"
CDS_LIB"mstr_standard";
"B \NAC \NWC"2;
"S \NAC"
BN"15"144;
%"TAP"
"6","(-2850,2750)","2","mstr_standard","I123";
;
HDL_TAP"TRUE"
BODY_TYPE"PLUMBING"
CDS_LIB"mstr_standard";
"B \NAC \NWC"2;
"S \NAC"
BN"16"143;
%"TAP"
"6","(-2850,2800)","2","mstr_standard","I124";
;
HDL_TAP"TRUE"
BODY_TYPE"PLUMBING"
CDS_LIB"mstr_standard";
"B \NAC \NWC"2;
"S \NAC"
BN"17"142;
%"TAP"
"6","(-2850,2950)","2","mstr_standard","I125";
;
HDL_TAP"TRUE"
BODY_TYPE"PLUMBING"
CDS_LIB"mstr_standard";
"B \NAC \NWC"3;
"S \NAC"
BN"1"136;
%"TAP"
"6","(-2850,2900)","2","mstr_standard","I126";
;
HDL_TAP"TRUE"
BODY_TYPE"PLUMBING"
CDS_LIB"mstr_standard";
"B \NAC \NWC"3;
"S \NAC"
BN"0"137;
%"TAP"
"6","(-2850,3000)","2","mstr_standard","I127";
;
HDL_TAP"TRUE"
BODY_TYPE"PLUMBING"
CDS_LIB"mstr_standard";
"B \NAC \NWC"3;
"S \NAC"
BN"2"135;
%"TAP"
"6","(-2850,3050)","2","mstr_standard","I128";
;
HDL_TAP"TRUE"
BODY_TYPE"PLUMBING"
CDS_LIB"mstr_standard";
"B \NAC \NWC"3;
"S \NAC"
BN"3"134;
%"TAP"
"6","(-2850,3100)","2","mstr_standard","I129";
;
HDL_TAP"TRUE"
BODY_TYPE"PLUMBING"
CDS_LIB"mstr_standard";
"B \NAC \NWC"3;
"S \NAC"
BN"4"133;
%"TAP"
"6","(-5575,1100)","0","mstr_standard","I13";
;
HDL_TAP"TRUE"
BODY_TYPE"PLUMBING"
CDS_LIB"mstr_standard";
"B \NAC \NWC"10;
"S \NAC"
BN"0"47;
%"TAP"
"6","(-2850,3150)","2","mstr_standard","I130";
;
HDL_TAP"TRUE"
BODY_TYPE"PLUMBING"
CDS_LIB"mstr_standard";
"B \NAC \NWC"3;
"S \NAC"
BN"5"132;
%"TAP"
"6","(-2850,3250)","2","mstr_standard","I131";
;
HDL_TAP"TRUE"
BODY_TYPE"PLUMBING"
CDS_LIB"mstr_standard";
"B \NAC \NWC"3;
"S \NAC"
BN"7"13;
%"TAP"
"6","(-2850,3200)","2","mstr_standard","I132";
;
HDL_TAP"TRUE"
BODY_TYPE"PLUMBING"
CDS_LIB"mstr_standard";
"B \NAC \NWC"3;
"S \NAC"
BN"6"131;
%"TAP"
"6","(-2850,3300)","2","mstr_standard","I133";
;
HDL_TAP"TRUE"
BODY_TYPE"PLUMBING"
CDS_LIB"mstr_standard";
"B \NAC \NWC"3;
"S \NAC"
BN"8"130;
%"TAP"
"6","(-2850,3350)","2","mstr_standard","I134";
;
HDL_TAP"TRUE"
BODY_TYPE"PLUMBING"
CDS_LIB"mstr_standard";
"B \NAC \NWC"3;
"S \NAC"
BN"9"129;
%"TAP"
"6","(-2850,3400)","2","mstr_standard","I135";
;
HDL_TAP"TRUE"
BODY_TYPE"PLUMBING"
CDS_LIB"mstr_standard";
"B \NAC \NWC"3;
"S \NAC"
BN"10"128;
%"TAP"
"6","(-2850,3500)","2","mstr_standard","I136";
;
HDL_TAP"TRUE"
BODY_TYPE"PLUMBING"
CDS_LIB"mstr_standard";
"B \NAC \NWC"3;
"S \NAC"
BN"12"126;
%"TAP"
"6","(-2850,3450)","2","mstr_standard","I137";
;
HDL_TAP"TRUE"
BODY_TYPE"PLUMBING"
CDS_LIB"mstr_standard";
"B \NAC \NWC"3;
"S \NAC"
BN"11"127;
%"TAP"
"6","(-2850,3550)","2","mstr_standard","I138";
;
HDL_TAP"TRUE"
BODY_TYPE"PLUMBING"
CDS_LIB"mstr_standard";
"B \NAC \NWC"3;
"S \NAC"
BN"13"125;
%"TAP"
"6","(-2850,3650)","2","mstr_standard","I139";
;
HDL_TAP"TRUE"
BODY_TYPE"PLUMBING"
CDS_LIB"mstr_standard";
"B \NAC \NWC"3;
"S \NAC"
BN"15"123;
%"TAP"
"6","(-5575,1150)","0","mstr_standard","I14";
;
HDL_TAP"TRUE"
BODY_TYPE"PLUMBING"
CDS_LIB"mstr_standard";
"B \NAC \NWC"10;
"S \NAC"
BN"1"46;
%"TAP"
"6","(-2850,3600)","2","mstr_standard","I140";
;
HDL_TAP"TRUE"
BODY_TYPE"PLUMBING"
CDS_LIB"mstr_standard";
"B \NAC \NWC"3;
"S \NAC"
BN"14"124;
%"TAP"
"6","(-2850,3750)","2","mstr_standard","I141";
;
HDL_TAP"TRUE"
BODY_TYPE"PLUMBING"
CDS_LIB"mstr_standard";
"B \NAC \NWC"3;
"S \NAC"
BN"17"121;
%"TAP"
"6","(-2850,3700)","2","mstr_standard","I142";
;
HDL_TAP"TRUE"
BODY_TYPE"PLUMBING"
CDS_LIB"mstr_standard";
"B \NAC \NWC"3;
"S \NAC"
BN"16"122;
%"TAP"
"6","(-2850,3900)","2","mstr_standard","I143";
;
HDL_TAP"TRUE"
BODY_TYPE"PLUMBING"
CDS_LIB"mstr_standard";
"B \NAC \NWC"1;
"S \NAC"
BN"1"16;
%"TAP"
"6","(-2850,3850)","2","mstr_standard","I144";
;
HDL_TAP"TRUE"
BODY_TYPE"PLUMBING"
CDS_LIB"mstr_standard";
"B \NAC \NWC"1;
"S \NAC"
BN"0"141;
%"TAP"
"6","(-2850,3950)","2","mstr_standard","I145";
;
HDL_TAP"TRUE"
BODY_TYPE"PLUMBING"
CDS_LIB"mstr_standard";
"B \NAC \NWC"1;
"S \NAC"
BN"2"140;
%"TAP"
"6","(-2850,4000)","2","mstr_standard","I146";
;
HDL_TAP"TRUE"
BODY_TYPE"PLUMBING"
CDS_LIB"mstr_standard";
"B \NAC \NWC"1;
"S \NAC"
BN"3"139;
%"TAP"
"6","(-5575,1200)","0","mstr_standard","I15";
;
HDL_TAP"TRUE"
BODY_TYPE"PLUMBING"
CDS_LIB"mstr_standard";
"B \NAC \NWC"10;
"S \NAC"
BN"2"45;
%"TAP"
"6","(-2850,4100)","2","mstr_standard","I157";
;
HDL_TAP"TRUE"
BODY_TYPE"PLUMBING"
CDS_LIB"mstr_standard";
"B \NAC \NWC"1;
"S \NAC"
BN"5"170;
%"TAP"
"6","(-2850,4050)","2","mstr_standard","I158";
;
HDL_TAP"TRUE"
BODY_TYPE"PLUMBING"
CDS_LIB"mstr_standard";
"B \NAC \NWC"1;
"S \NAC"
BN"4"138;
%"TAP"
"6","(-2850,4150)","2","mstr_standard","I159";
;
HDL_TAP"TRUE"
BODY_TYPE"PLUMBING"
CDS_LIB"mstr_standard";
"B \NAC \NWC"1;
"S \NAC"
BN"6"169;
%"TAP"
"6","(-5575,1300)","0","mstr_standard","I16";
;
HDL_TAP"TRUE"
BODY_TYPE"PLUMBING"
CDS_LIB"mstr_standard";
"B \NAC \NWC"10;
"S \NAC"
BN"4"43;
%"TAP"
"6","(-2850,4200)","2","mstr_standard","I160";
;
HDL_TAP"TRUE"
BODY_TYPE"PLUMBING"
CDS_LIB"mstr_standard";
"B \NAC \NWC"1;
"S \NAC"
BN"7"168;
%"TAP"
"6","(-2850,4250)","2","mstr_standard","I161";
;
HDL_TAP"TRUE"
BODY_TYPE"PLUMBING"
CDS_LIB"mstr_standard";
"B \NAC \NWC"1;
"S \NAC"
BN"8"167;
%"TAP"
"6","(-2850,4300)","2","mstr_standard","I162";
;
HDL_TAP"TRUE"
BODY_TYPE"PLUMBING"
CDS_LIB"mstr_standard";
"B \NAC \NWC"1;
"S \NAC"
BN"9"166;
%"TAP"
"6","(-2850,4350)","2","mstr_standard","I163";
;
HDL_TAP"TRUE"
BODY_TYPE"PLUMBING"
CDS_LIB"mstr_standard";
"B \NAC \NWC"1;
"S \NAC"
BN"10"165;
%"TAP"
"6","(-2850,4400)","2","mstr_standard","I164";
;
HDL_TAP"TRUE"
BODY_TYPE"PLUMBING"
CDS_LIB"mstr_standard";
"B \NAC \NWC"1;
"S \NAC"
BN"11"164;
%"TAP"
"6","(-2850,4450)","2","mstr_standard","I165";
;
HDL_TAP"TRUE"
BODY_TYPE"PLUMBING"
CDS_LIB"mstr_standard";
"B \NAC \NWC"1;
"S \NAC"
BN"12"163;
%"TAP"
"6","(-2850,4550)","2","mstr_standard","I166";
;
HDL_TAP"TRUE"
BODY_TYPE"PLUMBING"
CDS_LIB"mstr_standard";
"B \NAC \NWC"1;
"S \NAC"
BN"14"161;
%"TAP"
"6","(-2850,4500)","2","mstr_standard","I167";
;
HDL_TAP"TRUE"
BODY_TYPE"PLUMBING"
CDS_LIB"mstr_standard";
"B \NAC \NWC"1;
"S \NAC"
BN"13"162;
%"TAP"
"6","(-2850,4600)","2","mstr_standard","I168";
;
HDL_TAP"TRUE"
BODY_TYPE"PLUMBING"
CDS_LIB"mstr_standard";
"B \NAC \NWC"1;
"S \NAC"
BN"15"160;
%"TAP"
"6","(-2850,4650)","2","mstr_standard","I169";
;
HDL_TAP"TRUE"
BODY_TYPE"PLUMBING"
CDS_LIB"mstr_standard";
"B \NAC \NWC"1;
"S \NAC"
BN"16"159;
%"TAP"
"6","(-5575,1250)","0","mstr_standard","I17";
;
HDL_TAP"TRUE"
BODY_TYPE"PLUMBING"
CDS_LIB"mstr_standard";
"B \NAC \NWC"10;
"S \NAC"
BN"3"44;
%"TAP"
"6","(-2850,4700)","2","mstr_standard","I170";
;
HDL_TAP"TRUE"
BODY_TYPE"PLUMBING"
CDS_LIB"mstr_standard";
"B \NAC \NWC"1;
"S \NAC"
BN"17"158;
%"SKX_EXT_B"
"5","(-4175,2600)","0","chpset_lib","I172";
;
CDS_SEC"5"
LOCATION"U5D1"
PART_NUMBER"TBD"
MATERIAL"IC"
PACK_TYPE"BGA1"
CDS_LIB"chpset_lib"
SEC_TYPE"BGA1"
SEC"5"
CDS_LOCATION"U5D1"
ROOM"CPU0";
"DDR2_PAR"
$PN"V53"118;
"DDR2_ODT<0>"
$PN"AA50"117;
"DDR2_ODT<1>"
$PN"AA48"116;
"DDR2_ODT<2>"
$PN"V49"18;
"DDR2_ODT<3>"
$PN"AB47"115;
"DDR2_MA<0>"
$PN"AB53"114;
"DDR2_MA<1>"
$PN"AE58"113;
"DDR2_MA<2>"
$PN"AD57"157;
"DDR2_MA<3>"
$PN"W58"156;
"DDR2_MA<4>"
$PN"AA58"155;
"DDR2_MA<5>"
$PN"V59"154;
"DDR2_MA<6>"
$PN"AB59"153;
"DDR2_MA<7>"
$PN"AE60"152;
"DDR2_MA<8>"
$PN"AD59"151;
"DDR2_MA<9>"
$PN"AG58"150;
"DDR2_MA<10>"
$PN"AD55"149;
"DDR2_MA<11>"
$PN"AG60"148;
"DDR2_MA<12>"
$PN"AG62"147;
"DDR2_MA<13>"
$PN"AD53"146;
"DDR2_MA<14>"
$PN"W50"145;
"DDR2_MA<15>"
$PN"AE54"144;
"DDR2_MA<16>"
$PN"AA52"143;
"DDR2_MA<17>"
$PN"AC46"142;
"DDR2_ECC<0>"
$PN"AU72"47;
"DDR2_ECC<1>"
$PN"BA72"46;
"DDR2_ECC<2>"
$PN"AV69"45;
"DDR2_ECC<3>"
$PN"AY69"44;
"DDR2_ECC<4>"
$PN"AV73"43;
"DDR2_ECC<5>"
$PN"AY73"42;
"DDR2_ECC<6>"
$PN"AU70"41;
"DDR2_ECC<7>"
$PN"BA70"40;
"DDR2_DQS_DP<0>"
$PN"AM75"141;
"DDR2_DQS_DP<1>"
$PN"AB75"16;
"DDR2_DQS_DP<2>"
$PN"W70"140;
"DDR2_DQS_DP<3>"
$PN"AR66"139;
"DDR2_DQS_DP<4>"
$PN"Y39"138;
"DDR2_DQS_DP<5>"
$PN"Y33"170;
"DDR2_DQS_DP<6>"
$PN"AG30"169;
"DDR2_DQS_DP<7>"
$PN"AG24"168;
"DDR2_DQS_DP<8>"
$PN"AY71"167;
"DDR2_DQS_DP<9>"
$PN"AN76"166;
"DDR2_DQS_DP<10>"
$PN"AC76"165;
"DDR2_DQS_DP<11>"
$PN"V71"164;
"DDR2_DQS_DP<12>"
$PN"AN66"163;
"DDR2_DQS_DP<13>"
$PN"V39"162;
"DDR2_DQS_DP<14>"
$PN"V33"161;
"DDR2_DQS_DP<15>"
$PN"AE30"160;
"DDR2_DQS_DP<16>"
$PN"AE24"159;
"DDR2_DQS_DP<17>"
$PN"AV71"158;
"DDR2_DQS_DN<0>"
$PN"AL74"137;
"DDR2_DQS_DN<1>"
$PN"AA74"136;
"DDR2_DQS_DN<2>"
$PN"Y69"135;
"DDR2_DQS_DN<3>"
$PN"AU66"134;
"DDR2_DQS_DN<4>"
$PN"AB39"133;
"DDR2_DQS_DN<5>"
$PN"AB33"132;
"DDR2_DQS_DN<6>"
$PN"AJ30"131;
"DDR2_DQS_DN<7>"
$PN"AJ24"13;
"DDR2_DQS_DN<8>"
$PN"BB71"130;
"DDR2_DQS_DN<9>"
$PN"AP77"129;
"DDR2_DQS_DN<10>"
$PN"AD77"128;
"DDR2_DQS_DN<11>"
$PN"U72"127;
"DDR2_DQS_DN<12>"
$PN"AL66"126;
"DDR2_DQS_DN<13>"
$PN"T39"125;
"DDR2_DQS_DN<14>"
$PN"T33"124;
"DDR2_DQS_DN<15>"
$PN"AC30"123;
"DDR2_DQS_DN<16>"
$PN"AC24"122;
"DDR2_DQS_DN<17>"
$PN"AT71"121;
"DDR2_DQ<0>"
$PN"AR76"39;
"DDR2_DQ<1>"
$PN"AN74"38;
"DDR2_DQ<2>"
$PN"AK77"37;
"DDR2_DQ<3>"
$PN"AJ76"36;
"DDR2_DQ<4>"
$PN"AT75"21;
"DDR2_DQ<5>"
$PN"AR74"35;
"DDR2_DQ<6>"
$PN"AM77"34;
"DDR2_DQ<7>"
$PN"AK75"33;
"DDR2_DQ<8>"
$PN"AE76"32;
"DDR2_DQ<9>"
$PN"AC74"31;
"DDR2_DQ<10>"
$PN"Y77"84;
"DDR2_DQ<11>"
$PN"W76"83;
"DDR2_DQ<12>"
$PN"AF75"82;
"DDR2_DQ<13>"
$PN"AE74"81;
"DDR2_DQ<14>"
$PN"AB77"80;
"DDR2_DQ<15>"
$PN"Y75"79;
"DDR2_DQ<16>"
$PN"W72"78;
"DDR2_DQ<17>"
$PN"AA70"77;
"DDR2_DQ<18>"
$PN"R70"76;
"DDR2_DQ<19>"
$PN"T69"75;
"DDR2_DQ<20>"
$PN"AA72"74;
"DDR2_DQ<21>"
$PN"AB71"85;
"DDR2_DQ<22>"
$PN"T71"73;
"DDR2_DQ<23>"
$PN"V69"72;
"DDR2_DQ<24>"
$PN"AM67"71;
"DDR2_DQ<25>"
$PN"AT67"70;
"DDR2_DQ<26>"
$PN"AN64"69;
"DDR2_DQ<27>"
$PN"AR64"68;
"DDR2_DQ<28>"
$PN"AN68"67;
"DDR2_DQ<29>"
$PN"AR68"66;
"DDR2_DQ<30>"
$PN"AM65"65;
"DDR2_DQ<31>"
$PN"AT65"64;
"DDR2_DQ<32>"
$PN"U40"20;
"DDR2_DQ<33>"
$PN"AA40"63;
"DDR2_DQ<34>"
$PN"V37"19;
"DDR2_DQ<35>"
$PN"Y37"62;
"DDR2_DQ<36>"
$PN"V41"61;
"DDR2_DQ<37>"
$PN"Y41"60;
"DDR2_DQ<38>"
$PN"U38"59;
"DDR2_DQ<39>"
$PN"AA38"58;
"DDR2_DQ<40>"
$PN"U34"15;
"DDR2_DQ<41>"
$PN"AA34"57;
"DDR2_DQ<42>"
$PN"V31"56;
"DDR2_DQ<43>"
$PN"Y31"55;
"DDR2_DQ<44>"
$PN"V35"54;
"DDR2_DQ<45>"
$PN"Y35"53;
"DDR2_DQ<46>"
$PN"U32"52;
"DDR2_DQ<47>"
$PN"AA32"51;
"DDR2_DQ<48>"
$PN"AD31"50;
"DDR2_DQ<49>"
$PN"AH31"49;
"DDR2_DQ<50>"
$PN"AE28"48;
"DDR2_DQ<51>"
$PN"AG28"96;
"DDR2_DQ<52>"
$PN"AE32"17;
"DDR2_DQ<53>"
$PN"AG32"95;
"DDR2_DQ<54>"
$PN"AD29"14;
"DDR2_DQ<55>"
$PN"AH29"94;
"DDR2_DQ<56>"
$PN"AD25"93;
"DDR2_DQ<57>"
$PN"AH25"92;
"DDR2_DQ<58>"
$PN"AE22"91;
"DDR2_DQ<59>"
$PN"AG22"90;
"DDR2_DQ<60>"
$PN"AE26"89;
"DDR2_DQ<61>"
$PN"AG26"88;
"DDR2_DQ<62>"
$PN"AD23"87;
"DDR2_DQ<63>"
$PN"AH23"86;
"DDR2_CS_N<0>"
$PN"V51"112;
"DDR2_CS_N<1>"
$PN"AB49"111;
"DDR2_CS_N<2>"
$PN"W46"110;
"DDR2_CS_N<3>"
$PN"AA46"109;
"DDR2_CS_N<4>"
$PN"AB51"108;
"DDR2_CS_N<5>"
$PN"W48"107;
"DDR2_CS_N<6>"
$PN"T45"106;
"DDR2_CS_N<7>"
$PN"V45"105;
"DDR2_CLK_DP<0>"
$PN"AB55"30;
"DDR2_CLK_DP<1>"
$PN"V55"29;
"DDR2_CLK_DP<2>"
$PN"AB57"28;
"DDR2_CLK_DP<3>"
$PN"V57"27;
"DDR2_CLK_DN<0>"
$PN"AA54"26;
"DDR2_CLK_DN<1>"
$PN"W54"25;
"DDR2_CLK_DN<2>"
$PN"AA56"24;
"DDR2_CLK_DN<3>"
$PN"W56"23;
"DDR2_CKE<0>"
$PN"AA62"104;
"DDR2_CKE<1>"
$PN"AD63"103;
"DDR2_CKE<2>"
$PN"V63"102;
"DDR2_CKE<3>"
$PN"AB63"101;
"DDR2_CID<2>"
$PN"AB45"22;
"DDR2_BG<0>"
$PN"AA60"100;
"DDR2_BG<1>"
$PN"AE62"99;
"DDR2_BA<0>"
$PN"W52"98;
"DDR2_BA<1>"
$PN"AE56"97;
"DDR2_ALERT_N"
$PN"AD61"120;
"DDR2_ACT_N"
$PN"AB61"119;
%"TAP"
"6","(-5575,1350)","0","mstr_standard","I18";
;
HDL_TAP"TRUE"
BODY_TYPE"PLUMBING"
CDS_LIB"mstr_standard";
"B \NAC \NWC"10;
"S \NAC"
BN"5"42;
%"TAP"
"6","(-5575,1400)","0","mstr_standard","I19";
;
HDL_TAP"TRUE"
BODY_TYPE"PLUMBING"
CDS_LIB"mstr_standard";
"B \NAC \NWC"10;
"S \NAC"
BN"6"41;
%"TAP"
"6","(-5575,1450)","0","mstr_standard","I20";
;
HDL_TAP"TRUE"
BODY_TYPE"PLUMBING"
CDS_LIB"mstr_standard";
"B \NAC \NWC"10;
"S \NAC"
BN"7"40;
%"TAP"
"6","(-5575,1600)","0","mstr_standard","I21";
;
HDL_TAP"TRUE"
BODY_TYPE"PLUMBING"
CDS_LIB"mstr_standard";
"B \NAC \NWC"9;
"S \NAC"
BN"1"38;
%"TAP"
"6","(-5575,1550)","0","mstr_standard","I22";
;
HDL_TAP"TRUE"
BODY_TYPE"PLUMBING"
CDS_LIB"mstr_standard";
"B \NAC \NWC"9;
"S \NAC"
BN"0"39;
%"TAP"
"6","(-5575,1650)","0","mstr_standard","I23";
;
HDL_TAP"TRUE"
BODY_TYPE"PLUMBING"
CDS_LIB"mstr_standard";
"B \NAC \NWC"9;
"S \NAC"
BN"2"37;
%"TAP"
"6","(-5575,1700)","0","mstr_standard","I24";
;
HDL_TAP"TRUE"
BODY_TYPE"PLUMBING"
CDS_LIB"mstr_standard";
"B \NAC \NWC"9;
"S \NAC"
BN"3"36;
%"TAP"
"6","(-5575,1750)","0","mstr_standard","I25";
;
HDL_TAP"TRUE"
BODY_TYPE"PLUMBING"
CDS_LIB"mstr_standard";
"B \NAC \NWC"9;
"S \NAC"
BN"4"21;
%"TAP"
"6","(-5575,1800)","0","mstr_standard","I26";
;
HDL_TAP"TRUE"
BODY_TYPE"PLUMBING"
CDS_LIB"mstr_standard";
"B \NAC \NWC"9;
"S \NAC"
BN"5"35;
%"TAP"
"6","(-5575,1850)","0","mstr_standard","I27";
;
HDL_TAP"TRUE"
BODY_TYPE"PLUMBING"
CDS_LIB"mstr_standard";
"B \NAC \NWC"9;
"S \NAC"
BN"6"34;
%"TAP"
"6","(-5575,1900)","0","mstr_standard","I28";
;
HDL_TAP"TRUE"
BODY_TYPE"PLUMBING"
CDS_LIB"mstr_standard";
"B \NAC \NWC"9;
"S \NAC"
BN"7"33;
%"TAP"
"6","(-5575,1950)","0","mstr_standard","I29";
;
HDL_TAP"TRUE"
BODY_TYPE"PLUMBING"
CDS_LIB"mstr_standard";
"B \NAC \NWC"9;
"S \NAC"
BN"8"32;
%"TAP"
"6","(-5575,2100)","0","mstr_standard","I31";
;
HDL_TAP"TRUE"
BODY_TYPE"PLUMBING"
CDS_LIB"mstr_standard";
"B \NAC \NWC"9;
"S \NAC"
BN"11"83;
%"TAP"
"6","(-5575,2050)","0","mstr_standard","I32";
;
HDL_TAP"TRUE"
BODY_TYPE"PLUMBING"
CDS_LIB"mstr_standard";
"B \NAC \NWC"9;
"S \NAC"
BN"10"84;
%"TAP"
"6","(-5575,2000)","0","mstr_standard","I33";
;
HDL_TAP"TRUE"
BODY_TYPE"PLUMBING"
CDS_LIB"mstr_standard";
"B \NAC \NWC"9;
"S \NAC"
BN"9"31;
%"TAP"
"6","(-5575,2150)","0","mstr_standard","I34";
;
HDL_TAP"TRUE"
BODY_TYPE"PLUMBING"
CDS_LIB"mstr_standard";
"B \NAC \NWC"9;
"S \NAC"
BN"12"82;
%"TAP"
"6","(-5575,2200)","0","mstr_standard","I35";
;
HDL_TAP"TRUE"
BODY_TYPE"PLUMBING"
CDS_LIB"mstr_standard";
"B \NAC \NWC"9;
"S \NAC"
BN"13"81;
%"TAP"
"6","(-5575,2250)","0","mstr_standard","I36";
;
HDL_TAP"TRUE"
BODY_TYPE"PLUMBING"
CDS_LIB"mstr_standard";
"B \NAC \NWC"9;
"S \NAC"
BN"14"80;
%"TAP"
"6","(-5575,2300)","0","mstr_standard","I37";
;
HDL_TAP"TRUE"
BODY_TYPE"PLUMBING"
CDS_LIB"mstr_standard";
"B \NAC \NWC"9;
"S \NAC"
BN"15"79;
%"TAP"
"6","(-5575,2350)","0","mstr_standard","I38";
;
HDL_TAP"TRUE"
BODY_TYPE"PLUMBING"
CDS_LIB"mstr_standard";
"B \NAC \NWC"9;
"S \NAC"
BN"16"78;
%"TAP"
"6","(-5575,2400)","0","mstr_standard","I39";
;
HDL_TAP"TRUE"
BODY_TYPE"PLUMBING"
CDS_LIB"mstr_standard";
"B \NAC \NWC"9;
"S \NAC"
BN"17"77;
%"TAP"
"6","(-5575,2450)","0","mstr_standard","I40";
;
HDL_TAP"TRUE"
BODY_TYPE"PLUMBING"
CDS_LIB"mstr_standard";
"B \NAC \NWC"9;
"S \NAC"
BN"18"76;
%"TAP"
"6","(-5575,2500)","0","mstr_standard","I41";
;
HDL_TAP"TRUE"
BODY_TYPE"PLUMBING"
CDS_LIB"mstr_standard";
"B \NAC \NWC"9;
"S \NAC"
BN"19"75;
%"TAP"
"6","(-5575,2600)","0","mstr_standard","I42";
;
HDL_TAP"TRUE"
BODY_TYPE"PLUMBING"
CDS_LIB"mstr_standard";
"B \NAC \NWC"9;
"S \NAC"
BN"21"85;
%"TAP"
"6","(-5575,2550)","0","mstr_standard","I43";
;
HDL_TAP"TRUE"
BODY_TYPE"PLUMBING"
CDS_LIB"mstr_standard";
"B \NAC \NWC"9;
"S \NAC"
BN"20"74;
%"TAP"
"6","(-5575,2650)","0","mstr_standard","I44";
;
HDL_TAP"TRUE"
BODY_TYPE"PLUMBING"
CDS_LIB"mstr_standard";
"B \NAC \NWC"9;
"S \NAC"
BN"22"73;
%"TAP"
"6","(-5575,2700)","0","mstr_standard","I45";
;
HDL_TAP"TRUE"
BODY_TYPE"PLUMBING"
CDS_LIB"mstr_standard";
"B \NAC \NWC"9;
"S \NAC"
BN"23"72;
%"TAP"
"6","(-5575,2750)","0","mstr_standard","I46";
;
HDL_TAP"TRUE"
BODY_TYPE"PLUMBING"
CDS_LIB"mstr_standard";
"B \NAC \NWC"9;
"S \NAC"
BN"24"71;
%"TAP"
"6","(-5575,2850)","0","mstr_standard","I47";
;
HDL_TAP"TRUE"
BODY_TYPE"PLUMBING"
CDS_LIB"mstr_standard";
"B \NAC \NWC"9;
"S \NAC"
BN"26"69;
%"TAP"
"6","(-5575,2800)","0","mstr_standard","I48";
;
HDL_TAP"TRUE"
BODY_TYPE"PLUMBING"
CDS_LIB"mstr_standard";
"B \NAC \NWC"9;
"S \NAC"
BN"25"70;
%"TAP"
"6","(-5575,2900)","0","mstr_standard","I49";
;
HDL_TAP"TRUE"
BODY_TYPE"PLUMBING"
CDS_LIB"mstr_standard";
"B \NAC \NWC"9;
"S \NAC"
BN"27"68;
%"TAP"
"6","(-5575,650)","0","mstr_standard","I5";
;
HDL_TAP"TRUE"
BODY_TYPE"PLUMBING"
CDS_LIB"mstr_standard";
"B \NAC \NWC"12;
"S \NAC"
BN"0"26;
%"TAP"
"6","(-5575,2950)","0","mstr_standard","I50";
;
HDL_TAP"TRUE"
BODY_TYPE"PLUMBING"
CDS_LIB"mstr_standard";
"B \NAC \NWC"9;
"S \NAC"
BN"28"67;
%"TAP"
"6","(-5575,3000)","0","mstr_standard","I51";
;
HDL_TAP"TRUE"
BODY_TYPE"PLUMBING"
CDS_LIB"mstr_standard";
"B \NAC \NWC"9;
"S \NAC"
BN"29"66;
%"TAP"
"6","(-5575,3050)","0","mstr_standard","I52";
;
HDL_TAP"TRUE"
BODY_TYPE"PLUMBING"
CDS_LIB"mstr_standard";
"B \NAC \NWC"9;
"S \NAC"
BN"30"65;
%"TAP"
"6","(-5575,3100)","0","mstr_standard","I53";
;
HDL_TAP"TRUE"
BODY_TYPE"PLUMBING"
CDS_LIB"mstr_standard";
"B \NAC \NWC"9;
"S \NAC"
BN"31"64;
%"TAP"
"6","(-5575,3200)","0","mstr_standard","I54";
;
HDL_TAP"TRUE"
BODY_TYPE"PLUMBING"
CDS_LIB"mstr_standard";
"B \NAC \NWC"9;
"S \NAC"
BN"33"63;
%"TAP"
"6","(-5575,3250)","0","mstr_standard","I55";
;
HDL_TAP"TRUE"
BODY_TYPE"PLUMBING"
CDS_LIB"mstr_standard";
"B \NAC \NWC"9;
"S \NAC"
BN"34"19;
%"TAP"
"6","(-5575,3150)","0","mstr_standard","I56";
;
HDL_TAP"TRUE"
BODY_TYPE"PLUMBING"
CDS_LIB"mstr_standard";
"B \NAC \NWC"9;
"S \NAC"
BN"32"20;
%"TAP"
"6","(-5575,3350)","0","mstr_standard","I57";
;
HDL_TAP"TRUE"
BODY_TYPE"PLUMBING"
CDS_LIB"mstr_standard";
"B \NAC \NWC"9;
"S \NAC"
BN"36"61;
%"TAP"
"6","(-5575,3300)","0","mstr_standard","I58";
;
HDL_TAP"TRUE"
BODY_TYPE"PLUMBING"
CDS_LIB"mstr_standard";
"B \NAC \NWC"9;
"S \NAC"
BN"35"62;
%"TAP"
"6","(-5575,3400)","0","mstr_standard","I59";
;
HDL_TAP"TRUE"
BODY_TYPE"PLUMBING"
CDS_LIB"mstr_standard";
"B \NAC \NWC"9;
"S \NAC"
BN"37"60;
%"TAP"
"6","(-5575,700)","0","mstr_standard","I6";
;
HDL_TAP"TRUE"
BODY_TYPE"PLUMBING"
CDS_LIB"mstr_standard";
"B \NAC \NWC"12;
"S \NAC"
BN"1"25;
%"TAP"
"6","(-5575,3450)","0","mstr_standard","I60";
;
HDL_TAP"TRUE"
BODY_TYPE"PLUMBING"
CDS_LIB"mstr_standard";
"B \NAC \NWC"9;
"S \NAC"
BN"38"59;
%"TAP"
"6","(-5575,3500)","0","mstr_standard","I61";
;
HDL_TAP"TRUE"
BODY_TYPE"PLUMBING"
CDS_LIB"mstr_standard";
"B \NAC \NWC"9;
"S \NAC"
BN"39"58;
%"TAP"
"6","(-5575,3600)","0","mstr_standard","I62";
;
HDL_TAP"TRUE"
BODY_TYPE"PLUMBING"
CDS_LIB"mstr_standard";
"B \NAC \NWC"9;
"S \NAC"
BN"41"57;
%"TAP"
"6","(-5575,3550)","0","mstr_standard","I63";
;
HDL_TAP"TRUE"
BODY_TYPE"PLUMBING"
CDS_LIB"mstr_standard";
"B \NAC \NWC"9;
"S \NAC"
BN"40"15;
%"TAP"
"6","(-5575,3650)","0","mstr_standard","I64";
;
HDL_TAP"TRUE"
BODY_TYPE"PLUMBING"
CDS_LIB"mstr_standard";
"B \NAC \NWC"9;
"S \NAC"
BN"42"56;
%"TAP"
"6","(-5575,3700)","0","mstr_standard","I65";
;
HDL_TAP"TRUE"
BODY_TYPE"PLUMBING"
CDS_LIB"mstr_standard";
"B \NAC \NWC"9;
"S \NAC"
BN"43"55;
%"TAP"
"6","(-5575,3750)","0","mstr_standard","I66";
;
HDL_TAP"TRUE"
BODY_TYPE"PLUMBING"
CDS_LIB"mstr_standard";
"B \NAC \NWC"9;
"S \NAC"
BN"44"54;
%"TAP"
"6","(-5575,3800)","0","mstr_standard","I67";
;
HDL_TAP"TRUE"
BODY_TYPE"PLUMBING"
CDS_LIB"mstr_standard";
"B \NAC \NWC"9;
"S \NAC"
BN"45"53;
%"TAP"
"6","(-5575,3850)","0","mstr_standard","I68";
;
HDL_TAP"TRUE"
BODY_TYPE"PLUMBING"
CDS_LIB"mstr_standard";
"B \NAC \NWC"9;
"S \NAC"
BN"46"52;
%"TAP"
"6","(-5575,3900)","0","mstr_standard","I69";
;
HDL_TAP"TRUE"
BODY_TYPE"PLUMBING"
CDS_LIB"mstr_standard";
"B \NAC \NWC"9;
"S \NAC"
BN"47"51;
%"TAP"
"6","(-5575,750)","0","mstr_standard","I7";
;
HDL_TAP"TRUE"
BODY_TYPE"PLUMBING"
CDS_LIB"mstr_standard";
"B \NAC \NWC"12;
"S \NAC"
BN"2"24;
%"TAP"
"6","(-5575,3950)","0","mstr_standard","I70";
;
HDL_TAP"TRUE"
BODY_TYPE"PLUMBING"
CDS_LIB"mstr_standard";
"B \NAC \NWC"9;
"S \NAC"
BN"48"50;
%"TAP"
"6","(-5575,4000)","0","mstr_standard","I71";
;
HDL_TAP"TRUE"
BODY_TYPE"PLUMBING"
CDS_LIB"mstr_standard";
"B \NAC \NWC"9;
"S \NAC"
BN"49"49;
%"TAP"
"6","(-5575,4100)","0","mstr_standard","I73";
;
HDL_TAP"TRUE"
BODY_TYPE"PLUMBING"
CDS_LIB"mstr_standard";
"B \NAC \NWC"9;
"S \NAC"
BN"51"96;
%"TAP"
"6","(-5575,4050)","0","mstr_standard","I74";
;
HDL_TAP"TRUE"
BODY_TYPE"PLUMBING"
CDS_LIB"mstr_standard";
"B \NAC \NWC"9;
"S \NAC"
BN"50"48;
%"TAP"
"6","(-5575,4150)","0","mstr_standard","I75";
;
HDL_TAP"TRUE"
BODY_TYPE"PLUMBING"
CDS_LIB"mstr_standard";
"B \NAC \NWC"9;
"S \NAC"
BN"52"17;
%"TAP"
"6","(-5575,4200)","0","mstr_standard","I76";
;
HDL_TAP"TRUE"
BODY_TYPE"PLUMBING"
CDS_LIB"mstr_standard";
"B \NAC \NWC"9;
"S \NAC"
BN"53"95;
%"TAP"
"6","(-5575,4250)","0","mstr_standard","I77";
;
HDL_TAP"TRUE"
BODY_TYPE"PLUMBING"
CDS_LIB"mstr_standard";
"B \NAC \NWC"9;
"S \NAC"
BN"54"14;
%"TAP"
"6","(-5575,4300)","0","mstr_standard","I78";
;
HDL_TAP"TRUE"
BODY_TYPE"PLUMBING"
CDS_LIB"mstr_standard";
"B \NAC \NWC"9;
"S \NAC"
BN"55"94;
%"TAP"
"6","(-5575,4350)","0","mstr_standard","I79";
;
HDL_TAP"TRUE"
BODY_TYPE"PLUMBING"
CDS_LIB"mstr_standard";
"B \NAC \NWC"9;
"S \NAC"
BN"56"93;
%"TAP"
"6","(-5575,800)","0","mstr_standard","I8";
;
HDL_TAP"TRUE"
BODY_TYPE"PLUMBING"
CDS_LIB"mstr_standard";
"B \NAC \NWC"12;
"S \NAC"
BN"3"23;
%"TAP"
"6","(-5575,4400)","0","mstr_standard","I80";
;
HDL_TAP"TRUE"
BODY_TYPE"PLUMBING"
CDS_LIB"mstr_standard";
"B \NAC \NWC"9;
"S \NAC"
BN"57"92;
%"TAP"
"6","(-5575,4450)","0","mstr_standard","I81";
;
HDL_TAP"TRUE"
BODY_TYPE"PLUMBING"
CDS_LIB"mstr_standard";
"B \NAC \NWC"9;
"S \NAC"
BN"58"91;
%"TAP"
"6","(-5575,4500)","0","mstr_standard","I82";
;
HDL_TAP"TRUE"
BODY_TYPE"PLUMBING"
CDS_LIB"mstr_standard";
"B \NAC \NWC"9;
"S \NAC"
BN"59"90;
%"TAP"
"6","(-5575,4550)","0","mstr_standard","I83";
;
HDL_TAP"TRUE"
BODY_TYPE"PLUMBING"
CDS_LIB"mstr_standard";
"B \NAC \NWC"9;
"S \NAC"
BN"60"89;
%"TAP"
"6","(-5575,4600)","0","mstr_standard","I84";
;
HDL_TAP"TRUE"
BODY_TYPE"PLUMBING"
CDS_LIB"mstr_standard";
"B \NAC \NWC"9;
"S \NAC"
BN"61"88;
%"TAP"
"6","(-5575,4700)","0","mstr_standard","I85";
;
HDL_TAP"TRUE"
BODY_TYPE"PLUMBING"
CDS_LIB"mstr_standard";
"B \NAC \NWC"9;
"S \NAC"
BN"63"86;
%"TAP"
"6","(-5575,4650)","0","mstr_standard","I86";
;
HDL_TAP"TRUE"
BODY_TYPE"PLUMBING"
CDS_LIB"mstr_standard";
"B \NAC \NWC"9;
"S \NAC"
BN"62"87;
%"TAP"
"6","(-2850,750)","2","mstr_standard","I87";
;
HDL_TAP"TRUE"
BODY_TYPE"PLUMBING"
CDS_LIB"mstr_standard";
"B \NAC \NWC"8;
"S \NAC"
BN"0"98;
%"TAP"
"6","(-2850,800)","2","mstr_standard","I88";
;
HDL_TAP"TRUE"
BODY_TYPE"PLUMBING"
CDS_LIB"mstr_standard";
"B \NAC \NWC"8;
"S \NAC"
BN"1"97;
%"TAP"
"6","(-2850,850)","2","mstr_standard","I89";
;
HDL_TAP"TRUE"
BODY_TYPE"PLUMBING"
CDS_LIB"mstr_standard";
"B \NAC \NWC"7;
"S \NAC"
BN"0"100;
%"TAP"
"6","(-5575,850)","0","mstr_standard","I9";
;
HDL_TAP"TRUE"
BODY_TYPE"PLUMBING"
CDS_LIB"mstr_standard";
"B \NAC \NWC"11;
"S \NAC"
BN"0"30;
%"TAP"
"6","(-2850,900)","2","mstr_standard","I90";
;
HDL_TAP"TRUE"
BODY_TYPE"PLUMBING"
CDS_LIB"mstr_standard";
"B \NAC \NWC"7;
"S \NAC"
BN"1"99;
%"TAP"
"6","(-2850,1000)","2","mstr_standard","I91";
;
HDL_TAP"TRUE"
BODY_TYPE"PLUMBING"
CDS_LIB"mstr_standard";
"B \NAC \NWC"5;
"S \NAC"
BN"0"112;
%"TAP"
"6","(-2850,1100)","2","mstr_standard","I92";
;
HDL_TAP"TRUE"
BODY_TYPE"PLUMBING"
CDS_LIB"mstr_standard";
"B \NAC \NWC"5;
"S \NAC"
BN"2"110;
%"TAP"
"6","(-2850,1050)","2","mstr_standard","I93";
;
HDL_TAP"TRUE"
BODY_TYPE"PLUMBING"
CDS_LIB"mstr_standard";
"B \NAC \NWC"5;
"S \NAC"
BN"1"111;
%"TAP"
"6","(-2850,1200)","2","mstr_standard","I94";
;
HDL_TAP"TRUE"
BODY_TYPE"PLUMBING"
CDS_LIB"mstr_standard";
"B \NAC \NWC"5;
"S \NAC"
BN"4"108;
%"TAP"
"6","(-2850,1150)","2","mstr_standard","I95";
;
HDL_TAP"TRUE"
BODY_TYPE"PLUMBING"
CDS_LIB"mstr_standard";
"B \NAC \NWC"5;
"S \NAC"
BN"3"109;
%"TAP"
"6","(-2850,1250)","2","mstr_standard","I96";
;
HDL_TAP"TRUE"
BODY_TYPE"PLUMBING"
CDS_LIB"mstr_standard";
"B \NAC \NWC"5;
"S \NAC"
BN"5"107;
%"TAP"
"6","(-2850,1300)","2","mstr_standard","I97";
;
HDL_TAP"TRUE"
BODY_TYPE"PLUMBING"
CDS_LIB"mstr_standard";
"B \NAC \NWC"5;
"S \NAC"
BN"6"106;
%"TAP"
"6","(-2850,1350)","2","mstr_standard","I98";
;
HDL_TAP"TRUE"
BODY_TYPE"PLUMBING"
CDS_LIB"mstr_standard";
"B \NAC \NWC"5;
"S \NAC"
BN"7"105;
%"TAP"
"6","(-2850,1450)","2","mstr_standard","I99";
;
HDL_TAP"TRUE"
BODY_TYPE"PLUMBING"
CDS_LIB"mstr_standard";
"B \NAC \NWC"4;
"S \NAC"
BN"0"117;
END.
